#ISCELL
  pure_quanta quanta_title_block_c *
  *
#CELL
  pure_quanta lcmxo3lf2100c5bg256c *
  page36_i1
#CELL
  pure_quanta q_res *
  page36_i10
#ISCELL
  standard offpage *
  page36_i14
#ISCELL
  standard offpage *
  page36_i16
#ISCELL
  standard offpage *
  page36_i17
#ISCELL
  standard offpage *
  page36_i18
#ISCELL
  standard offpage *
  page36_i19
#CELL
  pure_quanta q_res *
  page36_i2
#ISCELL
  standard offpage *
  page36_i20
#ISCELL
  standard offpage *
  page36_i21
#ISCELL
  standard offpage *
  page36_i22
#ISCELL
  standard offpage *
  page36_i23
#ISCELL
  standard offpage *
  page36_i27
#ISCELL
  standard offpage *
  page36_i28
#ISCELL
  standard offpage *
  page36_i29
#CELL
  pure_quanta q_res *
  page36_i3
#ISCELL
  standard offpage *
  page36_i30
#CELL
  pure_quanta q_res *
  page36_i33
#CELL
  pure_quanta q_res *
  page36_i34
#CELL
  pure_quanta q_res *
  page36_i35
#CELL
  pure_quanta q_res *
  page36_i36
#ISCELL
  logical_power universal_power *
  page36_i37
#ISCELL
  logical_power universal_power *
  page36_i38
#CELL
  pure_quanta q_res *
  page36_i42
#CELL
  pure_quanta q_res *
  page36_i43
#ISCELL
  standard offpage *
  page36_i44
#ISCELL
  standard offpage *
  page36_i45
#CELL
  pure_quanta q_res *
  page36_i46
#CELL
  pure_quanta q_res *
  page36_i47
#ISCELL
  standard offpage *
  page36_i49
#CELL
  pure_quanta q_res *
  page36_i50
#ISCELL
  logical_power universal_power *
  page36_i51
#ISCELL
  standard offpage *
  page36_i52
#ISCELL
  standard offpage *
  page36_i54
#ISCELL
  standard offpage *
  page36_i55
#ISCELL
  standard offpage *
  page36_i56
#CELL
  pure_quanta q_res *
  page36_i57
#CELL
  pure_quanta q_res *
  page36_i58
#ISCELL
  standard offpage *
  page36_i61
#ISCELL
  standard offpage *
  page36_i62
#ISCELL
  standard offpage *
  page36_i63
#ISCELL
  standard offpage *
  page36_i64
#ISCELL
  standard offpage *
  page36_i65
#ISCELL
  standard offpage *
  page36_i66
#ISCELL
  standard offpage *
  page36_i67
#ISCELL
  standard offpage *
  page36_i68
#ISCELL
  standard offpage *
  page36_i69
#CELL
  pure_quanta q_res *
  page36_i7
#ISCELL
  standard offpage *
  page36_i74
#ISCELL
  standard offpage *
  page36_i75
#ISCELL
  standard offpage *
  page36_i76
#ISCELL
  standard offpage *
  page36_i77
#CELL
  pure_quanta q_res *
  page36_i78
#ISCELL
  standard offpage *
  page36_i79
#CELL
  pure_quanta q_res *
  page36_i8
#CELL
  pure_quanta q_res *
  page36_i80
#CELL
  pure_quanta q_res *
  page36_i81
#CELL
  pure_quanta q_res *
  page36_i82
#CELL
  pure_quanta q_res *
  page36_i9
